# T6G (Grand Teton) — schematic netlist excerpt (pin names and nets, part order shuffled) for the footprints in the layout excerpt that follows; sources: Cadence DE-HDL packaged netlist, KiCad conversion of 04192023_DAF0TMB3IC0_F0TG_MB_C_brd_V02_OCP.brd

C6053  Q_CAP  0.01UF 50V 10% X7R  pkg C0402  page 177 : A = P3V3_AUX ; B = GND
R16  Q_RES  10K 1% CHIP  pkg 0402LF  page 83 : A = RST_CPU0_PERST0_N ; B = GND
C550  Q_CAP  100UF 4V 20% X6S  pkg C0805  page 279 : A = P0V9_CPU0_RT0_2A ; B = GND

(kicad_pcb
	(version 20260206)
	(generator "pcbnew")
	(generator_version "10.0")
	(general
		(thickness 1.6)
		(legacy_teardrops no)
	)
	(paper "A4")
	(title_block
		(title "04192023_DAF0TMB3IC0_F0TG_MB_C_brd_V02_OCP.brd")
		(comment 1 "Grand Teton / footprints 5585-5587 of 8354")
	)
	(layers
		(0 "F.Cu" signal "TOP")
		(4 "In1.Cu" signal "GND")
		(6 "In2.Cu" signal "IN1")
		(8 "In3.Cu" signal "GND1")
		(10 "In4.Cu" signal "IN2")
		(12 "In5.Cu" signal "GND2")
		(14 "In6.Cu" signal "IN3")
		(16 "In7.Cu" signal "GND3")
		(18 "In8.Cu" signal "VCC")
		(20 "In9.Cu" signal "VCC1")
		(22 "In10.Cu" signal "GND4")
		(24 "In11.Cu" signal "IN4")
		(26 "In12.Cu" signal "GND5")
		(28 "In13.Cu" signal "IN5")
		(30 "In14.Cu" signal "GND6")
		(32 "In15.Cu" signal "IN6")
		(34 "In16.Cu" signal "GND7")
		(2 "B.Cu" signal "BOTTOM")
		(9 "F.Adhes" user "F.Adhesive")
		(11 "B.Adhes" user "B.Adhesive")
		(13 "F.Paste" user "Package Geometry/Pastemask Top")
		(15 "B.Paste" user "Package Geometry/Pastemask Bottom")
		(5 "F.SilkS" user "Ref Des/Silkscreen Top")
		(7 "B.SilkS" user "Ref Des/Silkscreen Bottom")
		(1 "F.Mask" user "Board Geometry/Soldermask Top")
		(3 "B.Mask" user "Board Geometry/Soldermask Bottom")
		(17 "Dwgs.User" user "User.Drawings")
		(19 "Cmts.User" user "User.Comments")
		(21 "Eco1.User" user "User.Eco1")
		(23 "Eco2.User" user "User.Eco2")
		(25 "Edge.Cuts" user "Board Geometry/Outline")
		(27 "Margin" user)
		(31 "F.CrtYd" user "Package Geometry/Place Bound Top")
		(29 "B.CrtYd" user "Package Geometry/Place Bound Bottom")
		(35 "F.Fab" user "Ref Des/Assembly Top")
		(33 "B.Fab" user "Ref Des/Assembly Bottom")
	)
	(footprint ""
		(layer "B.Cu")
		(at 134.262114 -32.818578 180)
		(property "Reference" "C6053"
			(at 0 0 0)
			(layer "B.SilkS")
			(hide yes)
			(effects
				(font
					(size 1.27 1.27)
				)
				(justify mirror)
			)
		)
		(property "Value" ""
			(at 0 0 0)
			(layer "B.Fab")
			(effects
				(font
					(size 1.27 1.27)
				)
				(justify mirror)
			)
		)
		(duplicate_pad_numbers_are_jumpers no)
		(fp_line
			(start 0.7874 0.4064)
			(end 0.7874 -0.4064)
			(stroke
				(width 0.1524)
				(type default)
			)
			(layer "B.SilkS")
		)
		(fp_line
			(start 0.7874 -0.4064)
			(end -0.7874 -0.4064)
			(stroke
				(width 0.1524)
				(type default)
			)
			(layer "B.SilkS")
		)
		(fp_line
			(start -0.7874 0.4064)
			(end 0.7874 0.4064)
			(stroke
				(width 0.1524)
				(type default)
			)
			(layer "B.SilkS")
		)
		(fp_line
			(start -0.7874 -0.4064)
			(end -0.7874 0.4064)
			(stroke
				(width 0.1524)
				(type default)
			)
			(layer "B.SilkS")
		)
		(fp_line
			(start 0.67945 0.3048)
			(end 0.67945 -0.305054)
			(stroke
				(width 0.1)
				(type default)
			)
			(layer "B.Fab")
		)
		(fp_line
			(start 0.67945 -0.305054)
			(end 0.12065 -0.305054)
			(stroke
				(width 0.1)
				(type default)
			)
			(layer "B.Fab")
		)
		(fp_line
			(start 0.12065 0.3048)
			(end 0.67945 0.3048)
			(stroke
				(width 0.1)
				(type default)
			)
			(layer "B.Fab")
		)
		(fp_line
			(start 0.12065 0.2794)
			(end 0.12065 0.3048)
			(stroke
				(width 0.1)
				(type default)
			)
			(layer "B.Fab")
		)
		(fp_line
			(start 0.12065 -0.2794)
			(end -0.12065 -0.2794)
			(stroke
				(width 0.1)
				(type default)
			)
			(layer "B.Fab")
		)
		(fp_line
			(start 0.12065 -0.305054)
			(end 0.12065 -0.2794)
			(stroke
				(width 0.1)
				(type default)
			)
			(layer "B.Fab")
		)
		(fp_line
			(start -0.120396 0.3048)
			(end -0.120396 0.2794)
			(stroke
				(width 0.1)
				(type default)
			)
			(layer "B.Fab")
		)
		(fp_line
			(start -0.120396 0.2794)
			(end 0.12065 0.2794)
			(stroke
				(width 0.1)
				(type default)
			)
			(layer "B.Fab")
		)
		(fp_line
			(start -0.12065 -0.2794)
			(end -0.12065 -0.3048)
			(stroke
				(width 0.1)
				(type default)
			)
			(layer "B.Fab")
		)
		(fp_line
			(start -0.12065 -0.3048)
			(end -0.67945 -0.3048)
			(stroke
				(width 0.1)
				(type default)
			)
			(layer "B.Fab")
		)
		(fp_line
			(start -0.67945 0.3048)
			(end -0.120396 0.3048)
			(stroke
				(width 0.1)
				(type default)
			)
			(layer "B.Fab")
		)
		(fp_line
			(start -0.67945 -0.3048)
			(end -0.67945 0.3048)
			(stroke
				(width 0.1)
				(type default)
			)
			(layer "B.Fab")
		)
		(pad "1" smd circle
			(at 0.40005 0)
			(size 0 0)
			(layers "B.Cu" "B.Mask" "B.Paste")
			(net "P3V3_AUX")
		)
		(pad "2" smd circle
			(at -0.40005 0)
			(size 0 0)
			(layers "B.Cu" "B.Mask" "B.Paste")
			(net "GND")
		)
	)
	(footprint ""
		(layer "B.Cu")
		(at 325.861426 -400.19605 180)
		(property "Reference" "C550"
			(at 0 0 0)
			(layer "B.SilkS")
			(hide yes)
			(effects
				(font
					(size 1.27 1.27)
				)
				(justify mirror)
			)
		)
		(property "Value" ""
			(at 0 0 0)
			(layer "B.Fab")
			(effects
				(font
					(size 1.27 1.27)
				)
				(justify mirror)
			)
		)
		(duplicate_pad_numbers_are_jumpers no)
		(fp_line
			(start 1.524 0.762)
			(end 1.524 -0.762)
			(stroke
				(width 0.1524)
				(type default)
			)
			(layer "B.SilkS")
		)
		(fp_line
			(start 1.524 -0.762)
			(end -1.524 -0.762)
			(stroke
				(width 0.1524)
				(type default)
			)
			(layer "B.SilkS")
		)
		(fp_line
			(start -1.524 0.762)
			(end 1.524 0.762)
			(stroke
				(width 0.1524)
				(type default)
			)
			(layer "B.SilkS")
		)
		(fp_line
			(start -1.524 -0.762)
			(end -1.524 0.762)
			(stroke
				(width 0.1524)
				(type default)
			)
			(layer "B.SilkS")
		)
		(fp_line
			(start 1.1049 0.724916)
			(end -1.1049 0.724916)
			(stroke
				(width 0.1)
				(type default)
			)
			(layer "B.Fab")
		)
		(fp_line
			(start 1.1049 -0.724916)
			(end 1.1049 0.724916)
			(stroke
				(width 0.1)
				(type default)
			)
			(layer "B.Fab")
		)
		(fp_line
			(start -1.1049 0.724916)
			(end -1.1049 -0.724916)
			(stroke
				(width 0.1)
				(type default)
			)
			(layer "B.Fab")
		)
		(fp_line
			(start -1.1049 -0.724916)
			(end 1.1049 -0.724916)
			(stroke
				(width 0.1)
				(type default)
			)
			(layer "B.Fab")
		)
		(pad "1" smd rect
			(at 0.889 0 180)
			(size 1.016 1.27)
			(layers "B.Cu" "B.Mask" "B.Paste")
			(net "P0V9_CPU0_RT0_2A")
		)
		(pad "2" smd rect
			(at -0.889 0 180)
			(size 1.016 1.27)
			(layers "B.Cu" "B.Mask" "B.Paste")
			(net "GND")
		)
	)
	(footprint ""
		(layer "B.Cu")
		(at 178.241452 -133.2738)
		(property "Reference" "R16"
			(at 0 0 0)
			(layer "B.SilkS")
			(hide yes)
			(effects
				(font
					(size 1.27 1.27)
				)
				(justify mirror)
			)
		)
		(property "Value" ""
			(at 0 0 0)
			(layer "B.Fab")
			(effects
				(font
					(size 1.27 1.27)
				)
				(justify mirror)
			)
		)
		(duplicate_pad_numbers_are_jumpers no)
		(fp_line
			(start -0.7874 -0.4064)
			(end -0.7874 0.4064)
			(stroke
				(width 0.1524)
				(type default)
			)
			(layer "B.SilkS")
		)
		(fp_line
			(start -0.7874 0.4064)
			(end 0.7874 0.4064)
			(stroke
				(width 0.1524)
				(type default)
			)
			(layer "B.SilkS")
		)
		(fp_line
			(start 0.7874 -0.4064)
			(end -0.7874 -0.4064)
			(stroke
				(width 0.1524)
				(type default)
			)
			(layer "B.SilkS")
		)
		(fp_line
			(start 0.7874 0.4064)
			(end 0.7874 -0.4064)
			(stroke
				(width 0.1524)
				(type default)
			)
			(layer "B.SilkS")
		)
		(fp_line
			(start -0.67945 -0.3048)
			(end -0.67945 0.3048)
			(stroke
				(width 0.1)
				(type default)
			)
			(layer "B.Fab")
		)
		(fp_line
			(start -0.67945 0.3048)
			(end -0.120396 0.3048)
			(stroke
				(width 0.1)
				(type default)
			)
			(layer "B.Fab")
		)
		(fp_line
			(start -0.12065 -0.3048)
			(end -0.67945 -0.3048)
			(stroke
				(width 0.1)
				(type default)
			)
			(layer "B.Fab")
		)
		(fp_line
			(start -0.12065 -0.2794)
			(end -0.12065 -0.3048)
			(stroke
				(width 0.1)
				(type default)
			)
			(layer "B.Fab")
		)
		(fp_line
			(start -0.120396 0.2794)
			(end 0.12065 0.2794)
			(stroke
				(width 0.1)
				(type default)
			)
			(layer "B.Fab")
		)
		(fp_line
			(start -0.120396 0.3048)
			(end -0.120396 0.2794)
			(stroke
				(width 0.1)
				(type default)
			)
			(layer "B.Fab")
		)
		(fp_line
			(start 0.12065 -0.305054)
			(end 0.12065 -0.2794)
			(stroke
				(width 0.1)
				(type default)
			)
			(layer "B.Fab")
		)
		(fp_line
			(start 0.12065 -0.2794)
			(end -0.12065 -0.2794)
			(stroke
				(width 0.1)
				(type default)
			)
			(layer "B.Fab")
		)
		(fp_line
			(start 0.12065 0.2794)
			(end 0.12065 0.3048)
			(stroke
				(width 0.1)
				(type default)
			)
			(layer "B.Fab")
		)
		(fp_line
			(start 0.12065 0.3048)
			(end 0.67945 0.3048)
			(stroke
				(width 0.1)
				(type default)
			)
			(layer "B.Fab")
		)
		(fp_line
			(start 0.67945 -0.305054)
			(end 0.12065 -0.305054)
			(stroke
				(width 0.1)
				(type default)
			)
			(layer "B.Fab")
		)
		(fp_line
			(start 0.67945 0.3048)
			(end 0.67945 -0.305054)
			(stroke
				(width 0.1)
				(type default)
			)
			(layer "B.Fab")
		)
		(pad "1" smd circle
			(at 0.40005 0 180)
			(size 0 0)
			(layers "B.Cu" "B.Mask" "B.Paste")
			(net "RST_CPU0_PERST0_N")
		)
		(pad "2" smd circle
			(at -0.40005 0 180)
			(size 0 0)
			(layers "B.Cu" "B.Mask" "B.Paste")
			(net "GND")
		)
	)
)
